(kicad_pcb
	(version 20260206)
	(generator "pcbnew")
	(generator_version "10.0")
	(general
		(thickness 1.6)
		(legacy_teardrops no)
	)
	(paper "A4")
	(title_block
		(title "v1-chassis-manager — T6M_CM_d_v01_1031_1645.brd")
		(comment 1 "Open CloudServer (Microsoft) / footprint 1507 of 2512 (U2), pads 483-598 of 1283")
	)
	(layers
		(0 "F.Cu" signal "TOP")
		(4 "In1.Cu" signal "GND1")
		(6 "In2.Cu" signal "IN1")
		(8 "In3.Cu" signal "VCC1")
		(10 "In4.Cu" signal "VCC2")
		(12 "In5.Cu" signal "GND2")
		(14 "In6.Cu" signal "IN2")
		(16 "In7.Cu" signal "IN3")
		(18 "In8.Cu" signal "GND3")
		(2 "B.Cu" signal "BOTTOM")
		(9 "F.Adhes" user "F.Adhesive")
		(11 "B.Adhes" user "B.Adhesive")
		(13 "F.Paste" user "Package Geometry/Pastemask Top")
		(15 "B.Paste" user "Package Geometry/Pastemask Bottom")
		(5 "F.SilkS" user "Ref Des/Silkscreen Top")
		(7 "B.SilkS" user "Ref Des/Silkscreen Bottom")
		(1 "F.Mask" user "Board Geometry/Soldermask Top")
		(3 "B.Mask" user "Board Geometry/Soldermask Bottom")
		(17 "Dwgs.User" user "User.Drawings")
		(19 "Cmts.User" user "User.Comments")
		(21 "Eco1.User" user "User.Eco1")
		(23 "Eco2.User" user "User.Eco2")
		(25 "Edge.Cuts" user "Board Geometry/Outline")
		(27 "Margin" user)
		(31 "F.CrtYd" user "Package Geometry/Place Bound Top")
		(29 "B.CrtYd" user "Package Geometry/Place Bound Bottom")
		(35 "F.Fab" user "Ref Des/Assembly Top")
		(33 "B.Fab" user "Ref Des/Assembly Bottom")
	)
	(footprint ""
		(layer "F.Cu")
		(at 58.000646 -75.799442)
		(property "Reference" "U2"
			(at -20.2438 -18.364708 0)
			(unlocked yes)
			(layer "F.SilkS")
			(effects
				(font
					(size 1.6002 1.1938)
					(thickness 0.1524)
				)
				(justify left)
			)
		)
		(property "Value" ""
			(at 0 0 0)
			(layer "F.Fab")
			(effects
				(font
					(size 1.27 1.27)
				)
			)
		)
		(duplicate_pad_numbers_are_jumpers no)
		(pad "AY9" smd circle
			(at -12.201398 6.42874)
			(size 0.3048 0.3048)
			(layers "F.Cu" "F.Mask" "F.Paste")
			(net "P2E_CPU_PCIE_SW_NODE1_TX_C_DN")
		)
		(pad "AY11" smd circle
			(at -11.439398 6.42874)
			(size 0.3048 0.3048)
			(layers "F.Cu" "F.Mask" "F.Paste")
			(net "P2E_CPU_PCIE_SW_NODE1_TX_C_DP")
		)
		(pad "AY12" smd circle
			(at -10.677398 6.42874)
			(size 0.3048 0.3048)
			(layers "F.Cu" "F.Mask" "F.Paste")
			(net "GND")
		)
		(pad "AY14" smd circle
			(at -9.915398 6.42874)
			(size 0.3048 0.3048)
			(layers "F.Cu" "F.Mask" "F.Paste")
			(net "GND")
		)
		(pad "AY15" smd circle
			(at -9.153398 6.42874)
			(size 0.3048 0.3048)
			(layers "F.Cu" "F.Mask" "F.Paste")
			(net "GND")
		)
		(pad "AY19" smd circle
			(at -7.47522 6.534404)
			(size 0.3048 0.3048)
			(layers "F.Cu" "F.Mask" "F.Paste")
			(net "GND")
		)
		(pad "AY21" smd circle
			(at -6.188964 6.153404)
			(size 0.3048 0.3048)
			(layers "F.Cu" "F.Mask" "F.Paste")
			(net "P1V05_NODE1")
		)
		(pad "AY23" smd circle
			(at -5.48894 6.153404)
			(size 0.3048 0.3048)
			(layers "F.Cu" "F.Mask" "F.Paste")
			(net "P1V05_NODE1")
		)
		(pad "AY29" smd circle
			(at -2.216404 6.153404)
			(size 0.3048 0.3048)
			(layers "F.Cu" "F.Mask" "F.Paste")
			(net "GND")
		)
		(pad "AY30" smd circle
			(at -1.51638 6.153404)
			(size 0.3048 0.3048)
			(layers "F.Cu" "F.Mask" "F.Paste")
			(net "GND")
		)
		(pad "AY37" smd circle
			(at 1.756156 6.153404)
			(size 0.3048 0.3048)
			(layers "F.Cu" "F.Mask" "F.Paste")
			(net "GND")
		)
		(pad "AY38" smd circle
			(at 2.45618 6.153404)
			(size 0.3048 0.3048)
			(layers "F.Cu" "F.Mask" "F.Paste")
			(net "P1V05_VCCPLL_DDR3_NODE1")
		)
		(pad "AY45" smd circle
			(at 5.728716 6.153404)
			(size 0.3048 0.3048)
			(layers "F.Cu" "F.Mask" "F.Paste")
			(net "GND")
		)
		(pad "AY46" smd circle
			(at 6.42874 6.153404)
			(size 0.3048 0.3048)
			(layers "F.Cu" "F.Mask" "F.Paste")
			(net "GND")
		)
		(pad "AY52" smd circle
			(at 9.153398 6.188964)
			(size 0.3048 0.3048)
			(layers "F.Cu" "F.Mask" "F.Paste")
			(net "GND")
		)
		(pad "AY53" smd circle
			(at 9.915398 6.188964)
			(size 0.3048 0.3048)
			(layers "F.Cu" "F.Mask" "F.Paste")
			(net "GND")
		)
		(pad "AY55" smd circle
			(at 10.677398 6.188964)
			(size 0.3048 0.3048)
			(layers "F.Cu" "F.Mask" "F.Paste")
			(net "GND")
		)
		(pad "AY56" smd circle
			(at 11.439398 6.188964)
			(size 0.3048 0.3048)
			(layers "F.Cu" "F.Mask" "F.Paste")
			(net "GND")
		)
		(pad "AY58" smd circle
			(at 12.201398 6.188964)
			(size 0.3048 0.3048)
			(layers "F.Cu" "F.Mask" "F.Paste")
			(net "GND")
		)
		(pad "AY59" smd circle
			(at 12.963398 6.188964)
			(size 0.3048 0.3048)
			(layers "F.Cu" "F.Mask" "F.Paste")
			(net "GND")
		)
		(pad "AY62" smd circle
			(at 14.204442 6.310884)
			(size 0.3048 0.3048)
			(layers "F.Cu" "F.Mask" "F.Paste")
			(net "GND")
		)
		(pad "AY63" smd circle
			(at 14.90091 6.218936)
			(size 0.3048 0.3048)
			(layers "F.Cu" "F.Mask" "F.Paste")
			(net "M1_DQ_NODE1_DQ52")
		)
		(pad "AY65" smd circle
			(at 15.639034 6.18744)
			(size 0.3048 0.3048)
			(layers "F.Cu" "F.Mask" "F.Paste")
			(net "M1_DQ_NODE1_DQ49")
		)
		(pad "B10" smd circle
			(at -11.823954 -12.63904)
			(size 0.3048 0.3048)
			(layers "F.Cu" "F.Mask" "F.Paste")
			(net "PD_NODE1_NTB_PERP")
		)
		(pad "B12" smd circle
			(at -10.897362 -12.640818)
			(size 0.3048 0.3048)
			(layers "F.Cu" "F.Mask" "F.Paste")
			(net "PD_NODE1_NTB_PERN")
		)
		(pad "B14" smd circle
			(at -9.868662 -12.805664)
			(size 0.3048 0.3048)
			(layers "F.Cu" "F.Mask" "F.Paste")
			(net "GND")
		)
		(pad "B17" smd circle
			(at -8.387842 -12.752324)
			(size 0.3048 0.3048)
			(layers "F.Cu" "F.Mask" "F.Paste")
			(net "PD_NODE1_NTB_PERP")
		)
		(pad "B19" smd circle
			(at -7.321042 -12.63904)
			(size 0.3048 0.3048)
			(layers "F.Cu" "F.Mask" "F.Paste")
			(net "PD_NODE1_NTB_PERN")
		)
		(pad "B21" smd circle
			(at -6.39445 -12.640818)
			(size 0.3048 0.3048)
			(layers "F.Cu" "F.Mask" "F.Paste")
			(net "PD_NODE1_NTB_PERN")
		)
		(pad "B23" smd circle
			(at -5.36575 -12.805664)
			(size 0.3048 0.3048)
			(layers "F.Cu" "F.Mask" "F.Paste")
			(net "GND")
		)
		(pad "B26" smd circle
			(at -3.88493 -12.752324)
			(size 0.3048 0.3048)
			(layers "F.Cu" "F.Mask" "F.Paste")
			(net "PD_NODE1_NTB_PERN")
		)
		(pad "B28" smd circle
			(at -2.81813 -12.63904)
			(size 0.3048 0.3048)
			(layers "F.Cu" "F.Mask" "F.Paste")
			(net "PD_CPU_NODE1_DFX_GPIO_GRP0_2")
		)
		(pad "B30" smd circle
			(at -1.891538 -12.640818)
			(size 0.3048 0.3048)
			(layers "F.Cu" "F.Mask" "F.Paste")
			(net "PD_CPU_NODE1_DFX_GPIO_GRP0_3")
		)
		(pad "B32" smd circle
			(at -0.862838 -12.805664)
			(size 0.3048 0.3048)
			(layers "F.Cu" "F.Mask" "F.Paste")
			(net "GND")
		)
		(pad "B35" smd circle
			(at 0.617982 -12.752324)
			(size 0.3048 0.3048)
			(layers "F.Cu" "F.Mask" "F.Paste")
			(net "PD_CPU_NODE1_DFX_GPIO_GRP1_4")
		)
		(pad "B37" smd circle
			(at 1.684782 -12.63904)
			(size 0.3048 0.3048)
			(layers "F.Cu" "F.Mask" "F.Paste")
			(net "GND")
		)
		(pad "B39" smd circle
			(at 2.611374 -12.640818)
			(size 0.3048 0.3048)
			(layers "F.Cu" "F.Mask" "F.Paste")
			(net "TP_CPU_NODE1_RSVD_MVT0")
		)
		(pad "B41" smd circle
			(at 3.640074 -12.805664)
			(size 0.3048 0.3048)
			(layers "F.Cu" "F.Mask" "F.Paste")
			(net "A_CPU_NODE1_NTB_CROSSLK_MODE")
		)
		(pad "B44" smd circle
			(at 5.120894 -12.752324)
			(size 0.3048 0.3048)
			(layers "F.Cu" "F.Mask" "F.Paste")
			(net "LPC_CPU_NODE1_R_CLKOUT0")
		)
		(pad "B46" smd circle
			(at 6.187694 -12.63904)
			(size 0.3048 0.3048)
			(layers "F.Cu" "F.Mask" "F.Paste")
			(net "GND")
		)
		(pad "B48" smd circle
			(at 7.114286 -12.640818)
			(size 0.3048 0.3048)
			(layers "F.Cu" "F.Mask" "F.Paste")
			(net "SPC_CPU_NODE1_RI_L")
		)
		(pad "B50" smd circle
			(at 8.142986 -12.805664)
			(size 0.3048 0.3048)
			(layers "F.Cu" "F.Mask" "F.Paste")
			(net "GND")
		)
		(pad "B53" smd circle
			(at 9.623806 -12.752324)
			(size 0.3048 0.3048)
			(layers "F.Cu" "F.Mask" "F.Paste")
			(net "TP_CPU_NODE1_ADR_COMPLETE")
		)
		(pad "B55" smd circle
			(at 10.690606 -12.63904)
			(size 0.3048 0.3048)
			(layers "F.Cu" "F.Mask" "F.Paste")
			(net "LAN1_DISABLE_N")
		)
		(pad "B57" smd circle
			(at 11.617198 -12.640818)
			(size 0.3048 0.3048)
			(layers "F.Cu" "F.Mask" "F.Paste")
			(net "PU_CPU_NODE1_BRD_ID0")
		)
		(pad "BA17" smd circle
			(at -8.175244 6.534404)
			(size 0.3048 0.3048)
			(layers "F.Cu" "F.Mask" "F.Paste")
			(net "GND")
		)
		(pad "BA21" smd circle
			(at -6.188964 6.915404)
			(size 0.3048 0.3048)
			(layers "F.Cu" "F.Mask" "F.Paste")
			(net "GND")
		)
		(pad "BA23" smd circle
			(at -5.48894 6.915404)
			(size 0.3048 0.3048)
			(layers "F.Cu" "F.Mask" "F.Paste")
			(net "GND")
		)
		(pad "BA25" smd circle
			(at -4.202684 6.534404)
			(size 0.3048 0.3048)
			(layers "F.Cu" "F.Mask" "F.Paste")
			(net "M1_DQ_NODE1_DQ17")
		)
		(pad "BA26" smd circle
			(at -3.50266 6.534404)
			(size 0.3048 0.3048)
			(layers "F.Cu" "F.Mask" "F.Paste")
			(net "GND")
		)
		(pad "BA29" smd circle
			(at -2.216404 6.915404)
			(size 0.3048 0.3048)
			(layers "F.Cu" "F.Mask" "F.Paste")
			(net "M1_DQ_NODE1_DQ22")
		)
		(pad "BA30" smd circle
			(at -1.51638 6.915404)
			(size 0.3048 0.3048)
			(layers "F.Cu" "F.Mask" "F.Paste")
			(net "GND")
		)
		(pad "BA32" smd circle
			(at -0.230124 6.534404)
			(size 0.3048 0.3048)
			(layers "F.Cu" "F.Mask" "F.Paste")
			(net "P1V05_VCCACLK_DDR3_NODE1")
		)
		(pad "BA34" smd circle
			(at 0.4699 6.534404)
			(size 0.3048 0.3048)
			(layers "F.Cu" "F.Mask" "F.Paste")
			(net "P1V5_SFRPLL_NODE1")
		)
		(pad "BA37" smd circle
			(at 1.756156 6.915404)
			(size 0.3048 0.3048)
			(layers "F.Cu" "F.Mask" "F.Paste")
			(net "GND")
		)
		(pad "BA38" smd circle
			(at 2.45618 6.915404)
			(size 0.3048 0.3048)
			(layers "F.Cu" "F.Mask" "F.Paste")
			(net "P1V05_VCCPLL_DDR3_NODE1")
		)
		(pad "BA41" smd circle
			(at 3.742436 6.534404)
			(size 0.3048 0.3048)
			(layers "F.Cu" "F.Mask" "F.Paste")
			(net "PV_VDDR_VCCCLK_DDR3_NODE1")
		)
		(pad "BA42" smd circle
			(at 4.44246 6.534404)
			(size 0.3048 0.3048)
			(layers "F.Cu" "F.Mask" "F.Paste")
			(net "GND")
		)
		(pad "BA45" smd circle
			(at 5.728716 6.915404)
			(size 0.3048 0.3048)
			(layers "F.Cu" "F.Mask" "F.Paste")
			(net "GND")
		)
		(pad "BA46" smd circle
			(at 6.42874 6.915404)
			(size 0.3048 0.3048)
			(layers "F.Cu" "F.Mask" "F.Paste")
			(net "GND")
		)
		(pad "BA49" smd circle
			(at 7.714996 6.534404)
			(size 0.3048 0.3048)
			(layers "F.Cu" "F.Mask" "F.Paste")
			(net "GND")
		)
		(pad "BA50" smd circle
			(at 8.41502 6.534404)
			(size 0.3048 0.3048)
			(layers "F.Cu" "F.Mask" "F.Paste")
			(net "M_DDR3_NODE1_ECC5")
		)
		(pad "BB2" smd circle
			(at -15.639034 7.321296)
			(size 0.3048 0.3048)
			(layers "F.Cu" "F.Mask" "F.Paste")
			(net "TP_CPU_NODE1_RP0_PERN5")
		)
		(pad "BB4" smd circle
			(at -14.90091 7.2898)
			(size 0.3048 0.3048)
			(layers "F.Cu" "F.Mask" "F.Paste")
			(net "TP_CPU_NODE1_RP0_PERP5")
		)
		(pad "BB5" smd circle
			(at -14.204442 7.197852)
			(size 0.3048 0.3048)
			(layers "F.Cu" "F.Mask" "F.Paste")
			(net "P2E_CPU_PCIE_SW_NODE1_RX_DP")
		)
		(pad "BB17" smd circle
			(at -8.175244 7.296404)
			(size 0.3048 0.3048)
			(layers "F.Cu" "F.Mask" "F.Paste")
			(net "TP_CPU_NODE1_RP0_PETN1")
		)
		(pad "BB19" smd circle
			(at -7.47522 7.296404)
			(size 0.3048 0.3048)
			(layers "F.Cu" "F.Mask" "F.Paste")
			(net "P2E_CPU_SATA_NODE1_TX_C_DN")
		)
		(pad "BB25" smd circle
			(at -4.202684 7.296404)
			(size 0.3048 0.3048)
			(layers "F.Cu" "F.Mask" "F.Paste")
			(net "M1_DQ_NODE1_DQ21")
		)
		(pad "BB26" smd circle
			(at -3.50266 7.296404)
			(size 0.3048 0.3048)
			(layers "F.Cu" "F.Mask" "F.Paste")
			(net "M1_DQ_NODE1_DQ19")
		)
		(pad "BB32" smd circle
			(at -0.230124 7.296404)
			(size 0.3048 0.3048)
			(layers "F.Cu" "F.Mask" "F.Paste")
			(net "GND")
		)
		(pad "BB34" smd circle
			(at 0.4699 7.296404)
			(size 0.3048 0.3048)
			(layers "F.Cu" "F.Mask" "F.Paste")
			(net "P1V5_SFRPLL_NODE1")
		)
		(pad "BB41" smd circle
			(at 3.742436 7.296404)
			(size 0.3048 0.3048)
			(layers "F.Cu" "F.Mask" "F.Paste")
			(net "PV_VDDR_VCCCLK_DDR3_NODE1")
		)
		(pad "BB42" smd circle
			(at 4.44246 7.296404)
			(size 0.3048 0.3048)
			(layers "F.Cu" "F.Mask" "F.Paste")
			(net "GND")
		)
		(pad "BB49" smd circle
			(at 7.714996 7.296404)
			(size 0.3048 0.3048)
			(layers "F.Cu" "F.Mask" "F.Paste")
			(net "M_DDR3_NODE1_ECC1")
		)
		(pad "BB50" smd circle
			(at 8.41502 7.296404)
			(size 0.3048 0.3048)
			(layers "F.Cu" "F.Mask" "F.Paste")
			(net "GND")
		)
		(pad "BB53" smd circle
			(at 9.534398 7.47522)
			(size 0.3048 0.3048)
			(layers "F.Cu" "F.Mask" "F.Paste")
			(net "GND")
		)
		(pad "BB54" smd circle
			(at 10.296398 7.47522)
			(size 0.3048 0.3048)
			(layers "F.Cu" "F.Mask" "F.Paste")
			(net "GND")
		)
		(pad "BB56" smd circle
			(at 11.058398 7.47522)
			(size 0.3048 0.3048)
			(layers "F.Cu" "F.Mask" "F.Paste")
			(net "GND")
		)
		(pad "BB57" smd circle
			(at 11.820398 7.47522)
			(size 0.3048 0.3048)
			(layers "F.Cu" "F.Mask" "F.Paste")
			(net "M1_DQ_NODE1_DQ44")
		)
		(pad "BB59" smd circle
			(at 12.582398 7.47522)
			(size 0.3048 0.3048)
			(layers "F.Cu" "F.Mask" "F.Paste")
			(net "M1_DQ_NODE1_DQ41")
		)
		(pad "BB60" smd circle
			(at 13.344398 7.47522)
			(size 0.3048 0.3048)
			(layers "F.Cu" "F.Mask" "F.Paste")
			(net "M1_DQ_NODE1_DQ45")
		)
		(pad "BB62" smd circle
			(at 14.204442 7.010908)
			(size 0.3048 0.3048)
			(layers "F.Cu" "F.Mask" "F.Paste")
			(net "GND")
		)
		(pad "BB63" smd circle
			(at 14.90091 7.107936)
			(size 0.3048 0.3048)
			(layers "F.Cu" "F.Mask" "F.Paste")
			(net "M_DDR3_NODE1_DQS6P")
		)
		(pad "BB65" smd circle
			(at 15.640812 7.114032)
			(size 0.3048 0.3048)
			(layers "F.Cu" "F.Mask" "F.Paste")
			(net "M_DDR3_NODE1_DQS6N")
		)
		(pad "BB66" smd oval
			(at 16.249396 7.463536 90)
			(size 0.254 0.3429)
			(layers "F.Cu" "F.Mask" "F.Paste")
			(net "GND")
		)
		(pad "BC1" smd oval
			(at -16.249396 7.6708 270)
			(size 0.254 0.3429)
			(layers "F.Cu" "F.Mask" "F.Paste")
			(net "GND")
		)
		(pad "BC3" smd circle
			(at -15.242794 7.901178)
			(size 0.3048 0.3048)
			(layers "F.Cu" "F.Mask" "F.Paste")
			(net "GND")
		)
		(pad "BC5" smd circle
			(at -14.08049 7.891272)
			(size 0.3048 0.3048)
			(layers "F.Cu" "F.Mask" "F.Paste")
			(net "GND")
		)
		(pad "BC7" smd circle
			(at -13.344398 7.714996)
			(size 0.3048 0.3048)
			(layers "F.Cu" "F.Mask" "F.Paste")
			(net "GND")
		)
		(pad "BC8" smd circle
			(at -12.582398 7.714996)
			(size 0.3048 0.3048)
			(layers "F.Cu" "F.Mask" "F.Paste")
			(net "TP_CPU_NODE1_RP0_PETP5")
		)
		(pad "BC10" smd circle
			(at -11.820398 7.714996)
			(size 0.3048 0.3048)
			(layers "F.Cu" "F.Mask" "F.Paste")
			(net "TP_CPU_NODE1_RP0_PETN5")
		)
		(pad "BC11" smd circle
			(at -11.058398 7.714996)
			(size 0.3048 0.3048)
			(layers "F.Cu" "F.Mask" "F.Paste")
			(net "GND")
		)
		(pad "BC13" smd circle
			(at -10.296398 7.714996)
			(size 0.3048 0.3048)
			(layers "F.Cu" "F.Mask" "F.Paste")
			(net "GND")
		)
		(pad "BC15" smd circle
			(at -9.4615 7.677404)
			(size 0.3048 0.3048)
			(layers "F.Cu" "F.Mask" "F.Paste")
			(net "GND")
		)
		(pad "BC21" smd circle
			(at -6.188964 7.677404)
			(size 0.3048 0.3048)
			(layers "F.Cu" "F.Mask" "F.Paste")
			(net "GND")
		)
		(pad "BC23" smd circle
			(at -5.48894 7.677404)
			(size 0.3048 0.3048)
			(layers "F.Cu" "F.Mask" "F.Paste")
			(net "GND")
		)
		(pad "BC29" smd circle
			(at -2.216404 7.677404)
			(size 0.3048 0.3048)
			(layers "F.Cu" "F.Mask" "F.Paste")
			(net "GND")
		)
		(pad "BC30" smd circle
			(at -1.51638 7.677404)
			(size 0.3048 0.3048)
			(layers "F.Cu" "F.Mask" "F.Paste")
			(net "GND")
		)
		(pad "BC37" smd circle
			(at 1.756156 7.677404)
			(size 0.3048 0.3048)
			(layers "F.Cu" "F.Mask" "F.Paste")
			(net "GND")
		)
		(pad "BC38" smd circle
			(at 2.45618 7.677404)
			(size 0.3048 0.3048)
			(layers "F.Cu" "F.Mask" "F.Paste")
			(net "M_NODE1_DIMM_RST_L")
		)
		(pad "BC45" smd circle
			(at 5.728716 7.677404)
			(size 0.3048 0.3048)
			(layers "F.Cu" "F.Mask" "F.Paste")
			(net "GND")
		)
		(pad "BC46" smd circle
			(at 6.42874 7.677404)
			(size 0.3048 0.3048)
			(layers "F.Cu" "F.Mask" "F.Paste")
			(net "GND")
		)
		(pad "BC62" smd circle
			(at 14.013688 7.689088)
			(size 0.3048 0.3048)
			(layers "F.Cu" "F.Mask" "F.Paste")
			(net "GND")
		)
		(pad "BC64" smd circle
			(at 15.247112 7.719314)
			(size 0.3048 0.3048)
			(layers "F.Cu" "F.Mask" "F.Paste")
			(net "M1_DQ_NODE1_DQ55")
		)
		(pad "BD2" smd circle
			(at -15.752318 8.388096)
			(size 0.3048 0.3048)
			(layers "F.Cu" "F.Mask" "F.Paste")
			(net "P2E_CPU_NIC2_NODE1_RX_DP")
		)
		(pad "BD4" smd circle
			(at -14.794738 8.440928)
			(size 0.3048 0.3048)
			(layers "F.Cu" "F.Mask" "F.Paste")
			(net "P2E_CPU_NIC2_NODE1_RX_DN")
		)
		(pad "BD7" smd circle
			(at -13.344398 8.41502)
			(size 0.3048 0.3048)
			(layers "F.Cu" "F.Mask" "F.Paste")
			(net "GND")
		)
		(pad "BD8" smd circle
			(at -12.582398 8.41502)
			(size 0.3048 0.3048)
			(layers "F.Cu" "F.Mask" "F.Paste")
			(net "P2E_CPU_NIC2_NODE1_TX_C_DN")
		)
		(pad "BD10" smd circle
			(at -11.820398 8.41502)
			(size 0.3048 0.3048)
			(layers "F.Cu" "F.Mask" "F.Paste")
			(net "P2E_CPU_NIC2_NODE1_TX_C_DP")
		)
		(pad "BD13" smd circle
			(at -10.161524 8.439404)
			(size 0.3048 0.3048)
			(layers "F.Cu" "F.Mask" "F.Paste")
			(net "M1_DQ_NODE1_DQ6")
		)
		(pad "BD15" smd circle
			(at -9.4615 8.439404)
			(size 0.3048 0.3048)
			(layers "F.Cu" "F.Mask" "F.Paste")
			(net "GND")
		)
		(pad "BD17" smd circle
			(at -8.175244 8.058404)
			(size 0.3048 0.3048)
			(layers "F.Cu" "F.Mask" "F.Paste")
			(net "TP_CPU_NODE1_RP0_PETP1")
		)
		(pad "BD19" smd circle
			(at -7.47522 8.058404)
			(size 0.3048 0.3048)
			(layers "F.Cu" "F.Mask" "F.Paste")
			(net "P2E_CPU_SATA_NODE1_TX_C_DP")
		)
		(pad "BD21" smd circle
			(at -6.188964 8.439404)
			(size 0.3048 0.3048)
			(layers "F.Cu" "F.Mask" "F.Paste")
			(net "GND")
		)
		(pad "BD23" smd circle
			(at -5.48894 8.439404)
			(size 0.3048 0.3048)
			(layers "F.Cu" "F.Mask" "F.Paste")
			(net "GND")
		)
		(pad "BD25" smd circle
			(at -4.202684 8.058404)
			(size 0.3048 0.3048)
			(layers "F.Cu" "F.Mask" "F.Paste")
			(net "GND")
		)
	)
)
